(kicad_pcb
	(version 20260206)
	(generator "pcbnew")
	(generator_version "10.0")
	(general
		(thickness 1.6)
		(legacy_teardrops no)
	)
	(paper "A4")
	(title_block
		(title "peb — Lightning_PEB_BRD.brd")
		(comment 1 "Lightning (Wiwynn / Facebook NVMe JBOF) / footprints 1888-1895 of 2563")
	)
	(layers
		(0 "F.Cu" signal "TOP")
		(4 "In1.Cu" signal "L2GND")
		(6 "In2.Cu" signal "L3")
		(8 "In3.Cu" signal "L4VCC")
		(10 "In4.Cu" signal "L5VCC")
		(12 "In5.Cu" signal "L6")
		(14 "In6.Cu" signal "L7GND")
		(2 "B.Cu" signal "BOTTOM")
		(9 "F.Adhes" user "F.Adhesive")
		(11 "B.Adhes" user "B.Adhesive")
		(13 "F.Paste" user "Package Geometry/Pastemask Top")
		(15 "B.Paste" user "Package Geometry/Pastemask Bottom")
		(5 "F.SilkS" user "Ref Des/Silkscreen Top")
		(7 "B.SilkS" user "Ref Des/Silkscreen Bottom")
		(1 "F.Mask" user "Board Geometry/Soldermask Top")
		(3 "B.Mask" user "Board Geometry/Soldermask Bottom")
		(17 "Dwgs.User" user "User.Drawings")
		(19 "Cmts.User" user "User.Comments")
		(21 "Eco1.User" user "User.Eco1")
		(23 "Eco2.User" user "User.Eco2")
		(25 "Edge.Cuts" user "Board Geometry/Outline")
		(27 "Margin" user)
		(31 "F.CrtYd" user "Package Geometry/Place Bound Top")
		(29 "B.CrtYd" user "Package Geometry/Place Bound Bottom")
		(35 "F.Fab" user "Ref Des/Assembly Top")
		(33 "B.Fab" user "Ref Des/Assembly Bottom")
	)
	(footprint ""
		(layer "B.Cu")
		(at 236.601 -37.0078 180)
		(property "Reference" "R7"
			(at 0 0 0)
			(layer "B.SilkS")
			(hide yes)
			(effects
				(font
					(size 1.27 1.27)
				)
				(justify mirror)
			)
		)
		(property "Value" "33R1J-GP"
			(at 3.3274 -1.3335 180)
			(unlocked yes)
			(layer "B.Fab")
			(hide yes)
			(effects
				(font
					(size 1.016 1.016)
					(thickness 0.1524)
				)
				(justify mirror)
			)
		)
		(property "Device Type" "R0201H12"
			(at 3.3274 -2.8575 180)
			(unlocked yes)
			(layer "B.Fab")
			(hide yes)
			(effects
				(font
					(size 1.016 1.016)
					(thickness 0.1524)
				)
				(justify mirror)
			)
		)
		(duplicate_pad_numbers_are_jumpers no)
		(fp_rect
			(start 0.2794 0.6477)
			(end -0.2794 -0.6477)
			(stroke
				(width 0)
				(type default)
			)
			(fill no)
			(layer "B.CrtYd")
		)
		(fp_rect
			(start 0.2794 0.6477)
			(end -0.2794 -0.6477)
			(stroke
				(width 0)
				(type default)
			)
			(fill no)
			(layer "B.Fab")
		)
		(pad "1" smd custom
			(at 0 -0.2794)
			(size 0.0762 0.0762)
			(layers "B.Cu" "B.Mask" "B.Paste")
			(net "PCIE_REFCLK_H1_N")
			(options
				(clearance outline)
				(anchor circle)
			)
			(primitives
				(gr_poly
					(pts
						(arc
							(start 0.1524 0.127)
							(mid 0.137521 0.162921)
							(end 0.1016 0.1778)
						)
						(arc
							(start -0.1016 0.1778)
							(mid -0.137521 0.162921)
							(end -0.1524 0.127)
						)
						(arc
							(start -0.1524 -0.127)
							(mid -0.137521 -0.162921)
							(end -0.1016 -0.1778)
						)
						(arc
							(start 0.1016 -0.1778)
							(mid 0.137521 -0.162921)
							(end 0.1524 -0.127)
						)
					)
					(width 0)
					(fill yes)
				)
			)
		)
		(pad "2" smd custom
			(at 0 0.2794)
			(size 0.0762 0.0762)
			(layers "B.Cu" "B.Mask" "B.Paste")
			(net "PCIE_REFCLK_H1_P")
			(options
				(clearance outline)
				(anchor circle)
			)
			(primitives
				(gr_poly
					(pts
						(arc
							(start 0.1524 0.127)
							(mid 0.137521 0.162921)
							(end 0.1016 0.1778)
						)
						(arc
							(start -0.1016 0.1778)
							(mid -0.137521 0.162921)
							(end -0.1524 0.127)
						)
						(arc
							(start -0.1524 -0.127)
							(mid -0.137521 -0.162921)
							(end -0.1016 -0.1778)
						)
						(arc
							(start 0.1016 -0.1778)
							(mid 0.137521 -0.162921)
							(end 0.1524 -0.127)
						)
					)
					(width 0)
					(fill yes)
				)
			)
		)
	)
	(footprint ""
		(layer "B.Cu")
		(at 178.0794 -67.691)
		(property "Reference" "PG25"
			(at 0 0 0)
			(layer "B.SilkS")
			(hide yes)
			(effects
				(font
					(size 1.27 1.27)
				)
				(justify mirror)
			)
		)
		(property "Value" "GAP-CLOSE-PWR-3-GP"
			(at -0.0254 -6.5786 0)
			(unlocked yes)
			(layer "B.Fab")
			(hide yes)
			(effects
				(font
					(size 1.016 1.016)
					(thickness 0.1524)
				)
				(justify mirror)
			)
		)
		(property "Device Type" "GAP-CLOSE-PWR-3"
			(at -0.0254 -8.255 0)
			(unlocked yes)
			(layer "B.Fab")
			(hide yes)
			(effects
				(font
					(size 1.016 1.016)
					(thickness 0.1524)
				)
				(justify mirror)
			)
		)
		(duplicate_pad_numbers_are_jumpers no)
		(fp_rect
			(start 0.7112 0.4572)
			(end -0.7112 -0.4572)
			(stroke
				(width 0)
				(type default)
			)
			(fill no)
			(layer "B.CrtYd")
		)
		(fp_poly
			(pts
				(xy 0.7112 -0.4572) (xy -0.7112 -0.4572) (xy -0.7112 0.4572) (xy 0.7112 0.4572)
			)
			(stroke
				(width 0)
				(type default)
			)
			(fill no)
			(layer "B.Fab")
		)
		(pad "1" smd rect
			(at 0.3048 0 180)
			(size 0.6604 0.762)
			(layers "B.Cu" "B.Mask" "B.Paste")
			(net "DUT_AVD_PCIE")
		)
		(pad "2" smd rect
			(at -0.3048 0 180)
			(size 0.6604 0.762)
			(layers "B.Cu" "B.Mask" "B.Paste")
			(net "P0V9")
		)
	)
	(footprint ""
		(layer "B.Cu")
		(at 235.966 -23.241 180)
		(property "Reference" "R786"
			(at 0 0 0)
			(layer "B.SilkS")
			(hide yes)
			(effects
				(font
					(size 1.27 1.27)
				)
				(justify mirror)
			)
		)
		(property "Value" "4K7R2F-GP"
			(at -0.064008 -3.993896 180)
			(unlocked yes)
			(layer "B.Fab")
			(hide yes)
			(effects
				(font
					(size 1.016 1.016)
					(thickness 0.1524)
				)
				(justify mirror)
			)
		)
		(property "Device Type" "R402H16"
			(at -0.064008 -5.517896 180)
			(unlocked yes)
			(layer "B.Fab")
			(hide yes)
			(effects
				(font
					(size 1.016 1.016)
					(thickness 0.1524)
				)
				(justify mirror)
			)
		)
		(duplicate_pad_numbers_are_jumpers no)
		(fp_line
			(start 0.508 -0.9398)
			(end 0.508 0.9398)
			(stroke
				(width 0.1524)
				(type default)
			)
			(layer "B.SilkS")
		)
		(fp_line
			(start -0.508 -0.9398)
			(end 0.508 -0.9398)
			(stroke
				(width 0.1524)
				(type default)
			)
			(layer "B.SilkS")
		)
		(fp_rect
			(start 0.508 0.9398)
			(end -0.508 -0.9398)
			(stroke
				(width 0)
				(type default)
			)
			(fill no)
			(layer "B.CrtYd")
		)
		(fp_rect
			(start 0.508 0.9398)
			(end -0.508 -0.9398)
			(stroke
				(width 0)
				(type default)
			)
			(fill no)
			(layer "B.Fab")
		)
		(pad "1" smd custom
			(at 0 -0.4445)
			(size 0.1397 0.1397)
			(layers "B.Cu" "B.Mask" "B.Paste")
			(net "BOOTSTRAP6")
			(options
				(clearance outline)
				(anchor circle)
			)
			(primitives
				(gr_poly
					(pts
						(arc
							(start -0.1778 0.2794)
							(mid -0.249642 0.249642)
							(end -0.2794 0.1778)
						)
						(arc
							(start -0.2794 -0.1778)
							(mid -0.249642 -0.249642)
							(end -0.1778 -0.2794)
						)
						(arc
							(start 0.1778 -0.2794)
							(mid 0.249642 -0.249642)
							(end 0.2794 -0.1778)
						)
						(arc
							(start 0.2794 0.1778)
							(mid 0.249642 0.249642)
							(end 0.1778 0.2794)
						)
					)
					(width 0)
					(fill yes)
				)
			)
		)
		(pad "2" smd custom
			(at 0 0.4445)
			(size 0.1397 0.1397)
			(layers "B.Cu" "B.Mask" "B.Paste")
			(net "BOOTSTRAP_R_6")
			(options
				(clearance outline)
				(anchor circle)
			)
			(primitives
				(gr_poly
					(pts
						(arc
							(start -0.1778 0.2794)
							(mid -0.249642 0.249642)
							(end -0.2794 0.1778)
						)
						(arc
							(start -0.2794 -0.1778)
							(mid -0.249642 -0.249642)
							(end -0.1778 -0.2794)
						)
						(arc
							(start 0.1778 -0.2794)
							(mid 0.249642 -0.249642)
							(end 0.2794 -0.1778)
						)
						(arc
							(start 0.2794 0.1778)
							(mid 0.249642 0.249642)
							(end 0.1778 0.2794)
						)
					)
					(width 0)
					(fill yes)
				)
			)
		)
	)
	(footprint ""
		(layer "B.Cu")
		(at 247.1166 -43.997372 -90)
		(property "Reference" "C449"
			(at 0 0 90)
			(layer "B.SilkS")
			(hide yes)
			(effects
				(font
					(size 1.27 1.27)
				)
				(justify mirror)
			)
		)
		(property "Value" "SCD1U16V1KX-1-GP"
			(at 2.8321 -1.7399 270)
			(unlocked yes)
			(layer "B.Fab")
			(hide yes)
			(effects
				(font
					(size 1.016 1.016)
					(thickness 0.1524)
				)
				(justify mirror)
			)
		)
		(property "Device Type" "C0201H13"
			(at 2.8321 -3.2639 270)
			(unlocked yes)
			(layer "B.Fab")
			(hide yes)
			(effects
				(font
					(size 1.016 1.016)
					(thickness 0.1524)
				)
				(justify mirror)
			)
		)
		(duplicate_pad_numbers_are_jumpers no)
		(fp_rect
			(start 0.2794 0.6477)
			(end -0.2794 -0.6477)
			(stroke
				(width 0)
				(type default)
			)
			(fill no)
			(layer "B.CrtYd")
		)
		(fp_rect
			(start 0.2794 0.6477)
			(end -0.2794 -0.6477)
			(stroke
				(width 0)
				(type default)
			)
			(fill no)
			(layer "B.Fab")
		)
		(pad "1" smd custom
			(at 0 -0.2794 90)
			(size 0.0762 0.0762)
			(layers "B.Cu" "B.Mask" "B.Paste")
			(net "DUT_VDD")
			(options
				(clearance outline)
				(anchor circle)
			)
			(primitives
				(gr_poly
					(pts
						(arc
							(start 0.1524 0.127)
							(mid 0.137521 0.162921)
							(end 0.1016 0.1778)
						)
						(arc
							(start -0.1016 0.1778)
							(mid -0.137521 0.162921)
							(end -0.1524 0.127)
						)
						(arc
							(start -0.1524 -0.127)
							(mid -0.137521 -0.162921)
							(end -0.1016 -0.1778)
						)
						(arc
							(start 0.1016 -0.1778)
							(mid 0.137521 -0.162921)
							(end 0.1524 -0.127)
						)
					)
					(width 0)
					(fill yes)
				)
			)
		)
		(pad "2" smd custom
			(at 0 0.2794 90)
			(size 0.0762 0.0762)
			(layers "B.Cu" "B.Mask" "B.Paste")
			(net "GND")
			(options
				(clearance outline)
				(anchor circle)
			)
			(primitives
				(gr_poly
					(pts
						(arc
							(start 0.1524 0.127)
							(mid 0.137521 0.162921)
							(end 0.1016 0.1778)
						)
						(arc
							(start -0.1016 0.1778)
							(mid -0.137521 0.162921)
							(end -0.1524 0.127)
						)
						(arc
							(start -0.1524 -0.127)
							(mid -0.137521 -0.162921)
							(end -0.1016 -0.1778)
						)
						(arc
							(start 0.1016 -0.1778)
							(mid 0.137521 -0.162921)
							(end 0.1524 -0.127)
						)
					)
					(width 0)
					(fill yes)
				)
			)
		)
	)
	(footprint ""
		(layer "B.Cu")
		(at 143.002508 -34.44113 180)
		(property "Reference" "C225"
			(at 0 0 0)
			(layer "B.SilkS")
			(hide yes)
			(effects
				(font
					(size 1.27 1.27)
				)
				(justify mirror)
			)
		)
		(property "Value" "SCD1U10V2KX-5GP"
			(at -1.1811 -2.7051 180)
			(unlocked yes)
			(layer "B.Fab")
			(hide yes)
			(effects
				(font
					(size 1.016 1.016)
					(thickness 0.1524)
				)
				(justify mirror)
			)
		)
		(property "Device Type" "C402H22"
			(at -1.1811 -4.2291 180)
			(unlocked yes)
			(layer "B.Fab")
			(hide yes)
			(effects
				(font
					(size 1.016 1.016)
					(thickness 0.1524)
				)
				(justify mirror)
			)
		)
		(duplicate_pad_numbers_are_jumpers no)
		(fp_rect
			(start 0.4318 0.9525)
			(end -0.4318 -0.9525)
			(stroke
				(width 0)
				(type default)
			)
			(fill no)
			(layer "B.CrtYd")
		)
		(fp_rect
			(start 0.4318 0.9525)
			(end -0.4318 -0.9525)
			(stroke
				(width 0)
				(type default)
			)
			(fill no)
			(layer "B.Fab")
		)
		(pad "1" smd custom
			(at 0 -0.4445)
			(size 0.1524 0.1524)
			(layers "B.Cu" "B.Mask" "B.Paste")
			(net "GND")
			(options
				(clearance outline)
				(anchor circle)
			)
			(primitives
				(gr_poly
					(pts
						(arc
							(start 0.3048 0.2032)
							(mid 0.275042 0.275042)
							(end 0.2032 0.3048)
						)
						(arc
							(start -0.2032 0.3048)
							(mid -0.275042 0.275042)
							(end -0.3048 0.2032)
						)
						(arc
							(start -0.3048 -0.2032)
							(mid -0.275042 -0.275042)
							(end -0.2032 -0.3048)
						)
						(arc
							(start 0.2032 -0.3048)
							(mid 0.275042 -0.275042)
							(end 0.3048 -0.2032)
						)
					)
					(width 0)
					(fill yes)
				)
			)
		)
		(pad "2" smd custom
			(at 0 0.4445)
			(size 0.1524 0.1524)
			(layers "B.Cu" "B.Mask" "B.Paste")
			(net "P3V3_STBY")
			(options
				(clearance outline)
				(anchor circle)
			)
			(primitives
				(gr_poly
					(pts
						(arc
							(start 0.3048 0.2032)
							(mid 0.275042 0.275042)
							(end 0.2032 0.3048)
						)
						(arc
							(start -0.2032 0.3048)
							(mid -0.275042 0.275042)
							(end -0.3048 0.2032)
						)
						(arc
							(start -0.3048 -0.2032)
							(mid -0.275042 -0.275042)
							(end -0.2032 -0.3048)
						)
						(arc
							(start 0.2032 -0.3048)
							(mid 0.275042 -0.275042)
							(end 0.3048 -0.2032)
						)
					)
					(width 0)
					(fill yes)
				)
			)
		)
	)
	(footprint ""
		(layer "B.Cu")
		(at 241.2238 -28.6766)
		(property "Reference" "TP263"
			(at 0 0 0)
			(layer "B.SilkS")
			(hide yes)
			(effects
				(font
					(size 1.27 1.27)
				)
				(justify mirror)
			)
		)
		(property "Value" "TPAD28-2-GP"
			(at 0.0127 -1.6637 0)
			(unlocked yes)
			(layer "B.Fab")
			(hide yes)
			(effects
				(font
					(size 1.016 1.016)
					(thickness 0.1524)
				)
				(justify mirror)
			)
		)
		(property "Device Type" "TPAD28"
			(at 0.0127 -3.1877 0)
			(unlocked yes)
			(layer "B.Fab")
			(hide yes)
			(effects
				(font
					(size 1.016 1.016)
					(thickness 0.1524)
				)
				(justify mirror)
			)
		)
		(duplicate_pad_numbers_are_jumpers no)
		(fp_poly
			(pts
				(arc
					(start 0.3556 0)
					(mid -0.3556 0)
					(end 0.3556 0)
				)
			)
			(stroke
				(width 0)
				(type default)
			)
			(fill no)
			(layer "B.CrtYd")
		)
		(fp_poly
			(pts
				(arc
					(start 0.6096 0)
					(mid -0.6096 0)
					(end 0.6096 0)
				)
			)
			(stroke
				(width 0)
				(type default)
			)
			(fill no)
			(layer "B.Fab")
		)
		(pad "1" smd circle
			(at 0 0 180)
			(size 0.7112 0.7112)
			(layers "B.Cu" "B.Mask" "B.Paste")
			(net "LBI_DATA_5")
		)
	)
	(footprint ""
		(layer "B.Cu")
		(at 39.54272 -114.53622 180)
		(property "Reference" "R444"
			(at 0 0 0)
			(layer "B.SilkS")
			(hide yes)
			(effects
				(font
					(size 1.27 1.27)
				)
				(justify mirror)
			)
		)
		(property "Value" "0R2J-2-GP"
			(at -0.064008 -3.993896 180)
			(unlocked yes)
			(layer "B.Fab")
			(hide yes)
			(effects
				(font
					(size 1.016 1.016)
					(thickness 0.1524)
				)
				(justify mirror)
			)
		)
		(property "Device Type" "R402H16"
			(at -0.064008 -5.517896 180)
			(unlocked yes)
			(layer "B.Fab")
			(hide yes)
			(effects
				(font
					(size 1.016 1.016)
					(thickness 0.1524)
				)
				(justify mirror)
			)
		)
		(duplicate_pad_numbers_are_jumpers no)
		(fp_line
			(start 0.508 -0.9398)
			(end 0.508 0.9398)
			(stroke
				(width 0.1524)
				(type default)
			)
			(layer "B.SilkS")
		)
		(fp_line
			(start -0.508 -0.9398)
			(end 0.508 -0.9398)
			(stroke
				(width 0.1524)
				(type default)
			)
			(layer "B.SilkS")
		)
		(fp_rect
			(start 0.508 0.9398)
			(end -0.508 -0.9398)
			(stroke
				(width 0)
				(type default)
			)
			(fill no)
			(layer "B.CrtYd")
		)
		(fp_rect
			(start 0.508 0.9398)
			(end -0.508 -0.9398)
			(stroke
				(width 0)
				(type default)
			)
			(fill no)
			(layer "B.Fab")
		)
		(pad "1" smd custom
			(at 0 -0.4445)
			(size 0.1397 0.1397)
			(layers "B.Cu" "B.Mask" "B.Paste")
			(net "GND")
			(options
				(clearance outline)
				(anchor circle)
			)
			(primitives
				(gr_poly
					(pts
						(arc
							(start -0.1778 0.2794)
							(mid -0.249642 0.249642)
							(end -0.2794 0.1778)
						)
						(arc
							(start -0.2794 -0.1778)
							(mid -0.249642 -0.249642)
							(end -0.1778 -0.2794)
						)
						(arc
							(start 0.1778 -0.2794)
							(mid 0.249642 -0.249642)
							(end 0.2794 -0.1778)
						)
						(arc
							(start 0.2794 0.1778)
							(mid 0.249642 0.249642)
							(end 0.1778 0.2794)
						)
					)
					(width 0)
					(fill yes)
				)
			)
		)
		(pad "2" smd custom
			(at 0 0.4445)
			(size 0.1397 0.1397)
			(layers "B.Cu" "B.Mask" "B.Paste")
			(net "RMII_PHY_BMC_RXD1")
			(options
				(clearance outline)
				(anchor circle)
			)
			(primitives
				(gr_poly
					(pts
						(arc
							(start -0.1778 0.2794)
							(mid -0.249642 0.249642)
							(end -0.2794 0.1778)
						)
						(arc
							(start -0.2794 -0.1778)
							(mid -0.249642 -0.249642)
							(end -0.1778 -0.2794)
						)
						(arc
							(start 0.1778 -0.2794)
							(mid 0.249642 -0.249642)
							(end 0.2794 -0.1778)
						)
						(arc
							(start 0.2794 0.1778)
							(mid 0.249642 0.249642)
							(end 0.1778 0.2794)
						)
					)
					(width 0)
					(fill yes)
				)
			)
		)
	)
	(footprint ""
		(layer "B.Cu")
		(at 59.2074 -128.524 90)
		(property "Reference" "R456"
			(at 0 0 90)
			(layer "B.SilkS")
			(hide yes)
			(effects
				(font
					(size 1.27 1.27)
				)
				(justify mirror)
			)
		)
		(property "Value" "4K7R2F-GP"
			(at -0.064008 -3.993896 90)
			(unlocked yes)
			(layer "B.Fab")
			(hide yes)
			(effects
				(font
					(size 1.016 1.016)
					(thickness 0.1524)
				)
				(justify mirror)
			)
		)
		(property "Device Type" "R402H16"
			(at -0.064008 -5.517896 90)
			(unlocked yes)
			(layer "B.Fab")
			(hide yes)
			(effects
				(font
					(size 1.016 1.016)
					(thickness 0.1524)
				)
				(justify mirror)
			)
		)
		(duplicate_pad_numbers_are_jumpers no)
		(fp_line
			(start 0.508 -0.9398)
			(end 0.508 0.9398)
			(stroke
				(width 0.1524)
				(type default)
			)
			(layer "B.SilkS")
		)
		(fp_line
			(start -0.508 -0.9398)
			(end 0.508 -0.9398)
			(stroke
				(width 0.1524)
				(type default)
			)
			(layer "B.SilkS")
		)
		(fp_rect
			(start 0.508 0.9398)
			(end -0.508 -0.9398)
			(stroke
				(width 0)
				(type default)
			)
			(fill no)
			(layer "B.CrtYd")
		)
		(fp_rect
			(start 0.508 0.9398)
			(end -0.508 -0.9398)
			(stroke
				(width 0)
				(type default)
			)
			(fill no)
			(layer "B.Fab")
		)
		(pad "1" smd custom
			(at 0 -0.4445 270)
			(size 0.1397 0.1397)
			(layers "B.Cu" "B.Mask" "B.Paste")
			(net "BMC_I2C14_MINI8_SCL_S")
			(options
				(clearance outline)
				(anchor circle)
			)
			(primitives
				(gr_poly
					(pts
						(arc
							(start -0.1778 0.2794)
							(mid -0.249642 0.249642)
							(end -0.2794 0.1778)
						)
						(arc
							(start -0.2794 -0.1778)
							(mid -0.249642 -0.249642)
							(end -0.1778 -0.2794)
						)
						(arc
							(start 0.1778 -0.2794)
							(mid 0.249642 -0.249642)
							(end 0.2794 -0.1778)
						)
						(arc
							(start 0.2794 0.1778)
							(mid 0.249642 0.249642)
							(end 0.1778 0.2794)
						)
					)
					(width 0)
					(fill yes)
				)
			)
		)
		(pad "2" smd custom
			(at 0 0.4445 270)
			(size 0.1397 0.1397)
			(layers "B.Cu" "B.Mask" "B.Paste")
			(net "P3V3_STBY")
			(options
				(clearance outline)
				(anchor circle)
			)
			(primitives
				(gr_poly
					(pts
						(arc
							(start -0.1778 0.2794)
							(mid -0.249642 0.249642)
							(end -0.2794 0.1778)
						)
						(arc
							(start -0.2794 -0.1778)
							(mid -0.249642 -0.249642)
							(end -0.1778 -0.2794)
						)
						(arc
							(start 0.1778 -0.2794)
							(mid 0.249642 -0.249642)
							(end 0.2794 -0.1778)
						)
						(arc
							(start 0.2794 0.1778)
							(mid 0.249642 0.249642)
							(end 0.1778 0.2794)
						)
					)
					(width 0)
					(fill yes)
				)
			)
		)
	)
)
